(kicad_pcb
	(version 20241229)
	(generator "pcbnew")
	(generator_version "9.0")
	(general
		(thickness 1.711)
		(legacy_teardrops no)
	)
	(paper "A4")
	(title_block
		(title "Antmicro Baseboard for Jetson AGX Thor")
		(date "2026-02-18")
		(rev "1.1.0")
		(company "Antmicro Ltd")
		(comment 1 "www.antmicro.com")
		(comment 9 "footprints 868-870 of 1170")
	)
	(layers
		(0 "F.Cu" signal)
		(4 "In1.Cu" signal)
		(6 "In2.Cu" signal)
		(8 "In3.Cu" signal)
		(10 "In4.Cu" jumper)
		(12 "In5.Cu" signal)
		(14 "In6.Cu" signal)
		(16 "In7.Cu" signal)
		(18 "In8.Cu" signal)
		(2 "B.Cu" signal)
		(9 "F.Adhes" user "F.Adhesive")
		(11 "B.Adhes" user "B.Adhesive")
		(13 "F.Paste" user)
		(15 "B.Paste" user)
		(5 "F.SilkS" user "F.Silkscreen")
		(7 "B.SilkS" user "B.Silkscreen")
		(1 "F.Mask" user)
		(3 "B.Mask" user)
		(17 "Dwgs.User" user "User.Drawings")
		(19 "Cmts.User" user "User.Comments")
		(21 "Eco1.User" user "User.Eco1")
		(23 "Eco2.User" user "User.Eco2")
		(25 "Edge.Cuts" user)
		(27 "Margin" user)
		(31 "F.CrtYd" user "F.Courtyard")
		(29 "B.CrtYd" user "B.Courtyard")
		(35 "F.Fab" user)
		(33 "B.Fab" user)
	)
	(footprint "antmicro-footprints:C_0402_1005Metric"
		(layer "B.Cu")
		(at 214.4 87.2 -90)
		(descr "Capacitor SMD 0402")
		(tags "capacitor SMD 0402")
		(property "Reference" "C125"
			(at 0.8 -0.4 90)
			(layer "B.SilkS")
			(effects
				(font
					(size 0.7 0.7)
					(thickness 0.15)
				)
				(justify left bottom mirror)
			)
		)
		(property "Value" "C_100n_0402"
			(at -1.022927 -2.155213 90)
			(layer "B.Fab")
			(effects
				(font
					(size 0.7 0.7)
					(thickness 0.15)
				)
				(justify left bottom mirror)
			)
		)
		(property "Datasheet" "https://www.murata.com/products/productdetail?partno=GRM155R61H104KE14%23"
			(at 0 0 90)
			(layer "B.Fab")
			(hide yes)
			(effects
				(font
					(size 1.27 1.27)
					(thickness 0.15)
				)
				(justify mirror)
			)
		)
		(property "Description" "SMD Multilayer Ceramic Capacitor, 0.1 µF, 50 V, 0402 [1005 Metric], ± 10%, X5R, GRM Series"
			(at 0 0 90)
			(layer "B.Fab")
			(hide yes)
			(effects
				(font
					(size 1.27 1.27)
					(thickness 0.15)
				)
				(justify mirror)
			)
		)
		(property "Manufacturer" "Murata"
			(at 0 0 90)
			(unlocked yes)
			(layer "B.Fab")
			(hide yes)
			(effects
				(font
					(size 1 1)
					(thickness 0.15)
				)
				(justify mirror)
			)
		)
		(property "MPN" "GRM155R61H104KE14D"
			(at 0 0 90)
			(unlocked yes)
			(layer "B.Fab")
			(hide yes)
			(effects
				(font
					(size 1 1)
					(thickness 0.15)
				)
				(justify mirror)
			)
		)
		(property "Val" "100n"
			(at 0 0 90)
			(unlocked yes)
			(layer "B.Fab")
			(hide yes)
			(effects
				(font
					(size 1 1)
					(thickness 0.15)
				)
				(justify mirror)
			)
		)
		(property "License" "Apache-2.0"
			(at 0 0 90)
			(unlocked yes)
			(layer "B.Fab")
			(hide yes)
			(effects
				(font
					(size 1 1)
					(thickness 0.15)
				)
				(justify mirror)
			)
		)
		(property "Author" "Antmicro"
			(at 0 0 90)
			(unlocked yes)
			(layer "B.Fab")
			(hide yes)
			(effects
				(font
					(size 1 1)
					(thickness 0.15)
				)
				(justify mirror)
			)
		)
		(property "Voltage" "50V"
			(at 0 0 90)
			(unlocked yes)
			(layer "B.Fab")
			(hide yes)
			(effects
				(font
					(size 1 1)
					(thickness 0.15)
				)
				(justify mirror)
			)
		)
		(property "Dielectric" "X5R"
			(at 0 0 90)
			(unlocked yes)
			(layer "B.Fab")
			(hide yes)
			(effects
				(font
					(size 1 1)
					(thickness 0.15)
				)
				(justify mirror)
			)
		)
		(sheetname "/USB DP Alt mode/")
		(sheetfile "usb_dp.kicad_sch")
		(attr smd)
		(fp_poly
			(pts
				(xy -0.925 0.47) (xy -0.925 -0.47) (xy 0.925 -0.47) (xy 0.925 0.47)
			)
			(stroke
				(width 0.05)
				(type default)
			)
			(fill no)
			(layer "B.CrtYd")
		)
		(fp_line
			(start -0.494 0.25)
			(end 0.504 0.25)
			(stroke
				(width 0.15)
				(type solid)
			)
			(layer "B.Fab")
		)
		(fp_line
			(start 0.504 0.25)
			(end 0.504 -0.248)
			(stroke
				(width 0.15)
				(type solid)
			)
			(layer "B.Fab")
		)
		(fp_line
			(start -0.494 -0.248)
			(end -0.494 0.25)
			(stroke
				(width 0.15)
				(type solid)
			)
			(layer "B.Fab")
		)
		(fp_line
			(start 0.504 -0.248)
			(end -0.494 -0.248)
			(stroke
				(width 0.15)
				(type solid)
			)
			(layer "B.Fab")
		)
		(fp_text user "Author: Antmicro"
			(at -0.939 -3.399 90)
			(layer "B.Fab")
			(effects
				(font
					(size 0.7 0.7)
					(thickness 0.15)
				)
				(justify left bottom mirror)
			)
		)
		(fp_text user "License: Apache-2.0"
			(at -0.939 -5.799 90)
			(layer "B.Fab")
			(effects
				(font
					(size 0.7 0.7)
					(thickness 0.15)
				)
				(justify left bottom mirror)
			)
		)
		(fp_text user "${REFERENCE}"
			(at -0.939 -4.599 90)
			(layer "B.Fab")
			(effects
				(font
					(size 0.7 0.7)
					(thickness 0.15)
				)
				(justify left bottom mirror)
			)
		)
		(pad "1" smd roundrect
			(at -0.48 0 270)
			(size 0.59 0.64)
			(layers "B.Cu" "B.Mask" "B.Paste")
			(roundrect_rratio 0.25)
			(net 2 "+3V3")
			(pintype "passive")
		)
		(pad "2" smd roundrect
			(at 0.48 0 270)
			(size 0.59 0.64)
			(layers "B.Cu" "B.Mask" "B.Paste")
			(roundrect_rratio 0.25)
			(net 1 "GND")
			(pintype "passive")
		)
	)
	(footprint "antmicro-footprints:R_0402_1005Metric"
		(layer "B.Cu")
		(at 145.6 65.2 90)
		(descr "Resistor SMD 0402")
		(tags "resistor SMD 0402")
		(property "Reference" "R244"
			(at -3.6 -0.4 90)
			(layer "B.SilkS")
			(effects
				(font
					(size 0.7 0.7)
					(thickness 0.15)
				)
				(justify right top mirror)
			)
		)
		(property "Value" "R_100k_0402"
			(at -1.011843 -1.772046 90)
			(layer "B.Fab")
			(effects
				(font
					(size 0.7 0.7)
					(thickness 0.15)
				)
				(justify right top mirror)
			)
		)
		(property "Datasheet" "https://www.bourns.com/docs/product-datasheets/cr.pdf"
			(at 0 0 90)
			(layer "B.Fab")
			(hide yes)
			(effects
				(font
					(size 1.27 1.27)
					(thickness 0.15)
				)
				(justify mirror)
			)
		)
		(property "Description" "SMD Chip Resistor, 100 kohm, ± 1%, 62.5 mW, 0402 [1005 Metric], Thick Film, General Purpose"
			(at 0 0 90)
			(layer "B.Fab")
			(hide yes)
			(effects
				(font
					(size 1.27 1.27)
					(thickness 0.15)
				)
				(justify mirror)
			)
		)
		(property "Manufacturer" "Bourns"
			(at 0 0 270)
			(unlocked yes)
			(layer "B.Fab")
			(hide yes)
			(effects
				(font
					(size 1 1)
					(thickness 0.15)
				)
				(justify mirror)
			)
		)
		(property "MPN" "CR0402-FX-1003GLF"
			(at 0 0 270)
			(unlocked yes)
			(layer "B.Fab")
			(hide yes)
			(effects
				(font
					(size 1 1)
					(thickness 0.15)
				)
				(justify mirror)
			)
		)
		(property "Val" "100k"
			(at 0 0 270)
			(unlocked yes)
			(layer "B.Fab")
			(hide yes)
			(effects
				(font
					(size 1 1)
					(thickness 0.15)
				)
				(justify mirror)
			)
		)
		(property "License" "Apache-2.0"
			(at 0 0 270)
			(unlocked yes)
			(layer "B.Fab")
			(hide yes)
			(effects
				(font
					(size 1 1)
					(thickness 0.15)
				)
				(justify mirror)
			)
		)
		(property "Author" "Antmicro"
			(at 0 0 270)
			(unlocked yes)
			(layer "B.Fab")
			(hide yes)
			(effects
				(font
					(size 1 1)
					(thickness 0.15)
				)
				(justify mirror)
			)
		)
		(property "Tolerance" "1%"
			(at 0 0 270)
			(unlocked yes)
			(layer "B.Fab")
			(hide yes)
			(effects
				(font
					(size 1 1)
					(thickness 0.15)
				)
				(justify mirror)
			)
		)
		(sheetname "/Peripherals/")
		(sheetfile "peripherals.kicad_sch")
		(attr smd exclude_from_pos_files exclude_from_bom dnp)
		(fp_poly
			(pts
				(xy -0.925 0.47) (xy -0.925 -0.47) (xy 0.925 -0.47) (xy 0.925 0.47)
			)
			(stroke
				(width 0.05)
				(type default)
			)
			(fill no)
			(layer "B.CrtYd")
		)
		(fp_poly
			(pts
				(xy -0.5 0.25) (xy -0.5 -0.25) (xy 0.5 -0.25) (xy 0.5 0.25)
			)
			(stroke
				(width 0.15)
				(type solid)
			)
			(fill no)
			(layer "B.Fab")
		)
		(fp_text user "Author: Antmicro"
			(at -0.95 -4.169 90)
			(layer "B.Fab")
			(effects
				(font
					(size 0.7 0.7)
					(thickness 0.15)
				)
				(justify right top mirror)
			)
		)
		(fp_text user "License: Apache-2.0"
			(at -0.949999 -5.169 90)
			(layer "B.Fab")
			(effects
				(font
					(size 0.7 0.7)
					(thickness 0.15)
				)
				(justify right top mirror)
			)
		)
		(fp_text user "${REFERENCE}"
			(at -0.95 -3.168 90)
			(layer "B.Fab")
			(effects
				(font
					(size 0.7 0.7)
					(thickness 0.15)
				)
				(justify right top mirror)
			)
		)
		(pad "1" smd roundrect
			(at -0.48 0 90)
			(size 0.59 0.64)
			(layers "B.Cu" "B.Mask" "B.Paste")
			(roundrect_rratio 0.25)
			(net 1 "GND")
			(pintype "passive")
		)
		(pad "2" smd roundrect
			(at 0.48 0 90)
			(size 0.59 0.64)
			(layers "B.Cu" "B.Mask" "B.Paste")
			(roundrect_rratio 0.25)
			(net 90 "/Peripherals/I2C_CONN_PEN")
			(pintype "passive")
		)
	)
	(footprint "antmicro-footprints:C_0402_1005Metric"
		(layer "B.Cu")
		(at 215.426 137.8)
		(descr "Capacitor SMD 0402")
		(tags "capacitor SMD 0402")
		(property "Reference" "C174"
			(at -1.6 0.71 0)
			(layer "B.SilkS")
			(effects
				(font
					(size 0.7 0.7)
					(thickness 0.15)
				)
				(justify right top mirror)
			)
		)
		(property "Value" "C_100n_0402"
			(at -1.022927 -2.155213 0)
			(layer "B.Fab")
			(effects
				(font
					(size 0.7 0.7)
					(thickness 0.15)
				)
				(justify right top mirror)
			)
		)
		(property "Datasheet" "https://www.murata.com/products/productdetail?partno=GRM155R61H104KE14%23"
			(at 0 0 0)
			(layer "B.Fab")
			(hide yes)
			(effects
				(font
					(size 1.27 1.27)
					(thickness 0.15)
				)
				(justify mirror)
			)
		)
		(property "Description" "SMD Multilayer Ceramic Capacitor, 0.1 µF, 50 V, 0402 [1005 Metric], ± 10%, X5R, GRM Series"
			(at 0 0 0)
			(layer "B.Fab")
			(hide yes)
			(effects
				(font
					(size 1.27 1.27)
					(thickness 0.15)
				)
				(justify mirror)
			)
		)
		(property "MPN" "GRM155R61H104KE14D"
			(at 0 0 180)
			(unlocked yes)
			(layer "B.Fab")
			(hide yes)
			(effects
				(font
					(size 1 1)
					(thickness 0.15)
				)
				(justify mirror)
			)
		)
		(property "Manufacturer" "Murata"
			(at 0 0 180)
			(unlocked yes)
			(layer "B.Fab")
			(hide yes)
			(effects
				(font
					(size 1 1)
					(thickness 0.15)
				)
				(justify mirror)
			)
		)
		(property "License" "Apache-2.0"
			(at 0 0 180)
			(unlocked yes)
			(layer "B.Fab")
			(hide yes)
			(effects
				(font
					(size 1 1)
					(thickness 0.15)
				)
				(justify mirror)
			)
		)
		(property "Author" "Antmicro"
			(at 0 0 180)
			(unlocked yes)
			(layer "B.Fab")
			(hide yes)
			(effects
				(font
					(size 1 1)
					(thickness 0.15)
				)
				(justify mirror)
			)
		)
		(property "Val" "100n"
			(at 0 0 180)
			(unlocked yes)
			(layer "B.Fab")
			(hide yes)
			(effects
				(font
					(size 1 1)
					(thickness 0.15)
				)
				(justify mirror)
			)
		)
		(property "Voltage" "50V"
			(at 0 0 180)
			(unlocked yes)
			(layer "B.Fab")
			(hide yes)
			(effects
				(font
					(size 1 1)
					(thickness 0.15)
				)
				(justify mirror)
			)
		)
		(property "Dielectric" "X5R"
			(at 0 0 180)
			(unlocked yes)
			(layer "B.Fab")
			(hide yes)
			(effects
				(font
					(size 1 1)
					(thickness 0.15)
				)
				(justify mirror)
			)
		)
		(sheetname "/SFP/")
		(sheetfile "sfp.kicad_sch")
		(attr smd)
		(fp_poly
			(pts
				(xy -0.925 0.47) (xy -0.925 -0.47) (xy 0.925 -0.47) (xy 0.925 0.47)
			)
			(stroke
				(width 0.05)
				(type default)
			)
			(fill no)
			(layer "B.CrtYd")
		)
		(fp_line
			(start -0.494 -0.248)
			(end -0.494 0.25)
			(stroke
				(width 0.15)
				(type solid)
			)
			(layer "B.Fab")
		)
		(fp_line
			(start -0.494 0.25)
			(end 0.504 0.25)
			(stroke
				(width 0.15)
				(type solid)
			)
			(layer "B.Fab")
		)
		(fp_line
			(start 0.504 -0.248)
			(end -0.494 -0.248)
			(stroke
				(width 0.15)
				(type solid)
			)
			(layer "B.Fab")
		)
		(fp_line
			(start 0.504 0.25)
			(end 0.504 -0.248)
			(stroke
				(width 0.15)
				(type solid)
			)
			(layer "B.Fab")
		)
		(fp_text user "${REFERENCE}"
			(at -0.939 -4.599 0)
			(layer "B.Fab")
			(effects
				(font
					(size 0.7 0.7)
					(thickness 0.15)
				)
				(justify right top mirror)
			)
		)
		(fp_text user "License: Apache-2.0"
			(at -0.939 -5.799 0)
			(layer "B.Fab")
			(effects
				(font
					(size 0.7 0.7)
					(thickness 0.15)
				)
				(justify right top mirror)
			)
		)
		(fp_text user "Author: Antmicro"
			(at -0.939 -3.399 0)
			(layer "B.Fab")
			(effects
				(font
					(size 0.7 0.7)
					(thickness 0.15)
				)
				(justify right top mirror)
			)
		)
		(pad "1" smd roundrect
			(at -0.48 0)
			(size 0.59 0.64)
			(layers "B.Cu" "B.Mask" "B.Paste")
			(roundrect_rratio 0.25)
			(net 1 "GND")
			(pintype "passive")
		)
		(pad "2" smd roundrect
			(at 0.48 0)
			(size 0.59 0.64)
			(layers "B.Cu" "B.Mask" "B.Paste")
			(roundrect_rratio 0.25)
			(net 379 "/SFP/SH")
			(pintype "passive")
		)
	)
)
